# S9S_MB_2U (Grand Teton) — schematic netlist excerpt (pin names and nets, part order shuffled) for the footprints in the layout excerpt that follows; sources: Cadence DE-HDL packaged netlist, KiCad conversion of 03242023_DA0F0TMBIJ0_F0T_Motherboard_J_brd_V01_OCP.brd

R4195  Q_RES  1K 1% CHIP  pkg 0402LF  page 170 : A = U272_2_ADD1 ; B = GND
R2695  Q_RES  1K 1% EMPTY  pkg 0402LF  page 227 : A = P3V3_AUX ; B = TCA9539_0_ADD0

(kicad_pcb
	(version 20260206)
	(generator "pcbnew")
	(generator_version "10.0")
	(general
		(thickness 1.6)
		(legacy_teardrops no)
	)
	(paper "A4")
	(title_block
		(title "03242023_DA0F0TMBIJ0_F0T_Motherboard_J_brd_V01_OCP.brd")
		(comment 1 "Grand Teton / footprints 1079-1080 of 6105")
	)
	(layers
		(0 "F.Cu" signal "TOP")
		(4 "In1.Cu" signal "GND")
		(6 "In2.Cu" signal "IN1")
		(8 "In3.Cu" signal "GND1")
		(10 "In4.Cu" signal "IN2")
		(12 "In5.Cu" signal "GND2")
		(14 "In6.Cu" signal "IN3")
		(16 "In7.Cu" signal "GND3")
		(18 "In8.Cu" signal "VCC")
		(20 "In9.Cu" signal "VCC1")
		(22 "In10.Cu" signal "GND4")
		(24 "In11.Cu" signal "IN4")
		(26 "In12.Cu" signal "GND5")
		(28 "In13.Cu" signal "IN5")
		(30 "In14.Cu" signal "GND6")
		(32 "In15.Cu" signal "IN6")
		(34 "In16.Cu" signal "GND7")
		(2 "B.Cu" signal "BOTTOM")
		(9 "F.Adhes" user "F.Adhesive")
		(11 "B.Adhes" user "B.Adhesive")
		(13 "F.Paste" user "Package Geometry/Pastemask Top")
		(15 "B.Paste" user "Package Geometry/Pastemask Bottom")
		(5 "F.SilkS" user "Ref Des/Silkscreen Top")
		(7 "B.SilkS" user "Ref Des/Silkscreen Bottom")
		(1 "F.Mask" user "Board Geometry/Soldermask Top")
		(3 "B.Mask" user "Board Geometry/Soldermask Bottom")
		(17 "Dwgs.User" user "User.Drawings")
		(19 "Cmts.User" user "User.Comments")
		(21 "Eco1.User" user "User.Eco1")
		(23 "Eco2.User" user "User.Eco2")
		(25 "Edge.Cuts" user "Board Geometry/Outline")
		(27 "Margin" user)
		(31 "F.CrtYd" user "Package Geometry/Place Bound Top")
		(29 "B.CrtYd" user "Package Geometry/Place Bound Bottom")
		(35 "F.Fab" user "Ref Des/Assembly Top")
		(33 "B.Fab" user "Ref Des/Assembly Bottom")
	)
	(footprint ""
		(layer "F.Cu")
		(at 14.689582 -423.629836 -90)
		(property "Reference" "R2695"
			(at 0 0 270)
			(layer "F.SilkS")
			(hide yes)
			(effects
				(font
					(size 1.27 1.27)
				)
			)
		)
		(property "Value" ""
			(at 0 0 270)
			(layer "F.Fab")
			(effects
				(font
					(size 1.27 1.27)
				)
			)
		)
		(duplicate_pad_numbers_are_jumpers no)
		(fp_line
			(start -0.7874 0.4064)
			(end -0.7874 -0.4064)
			(stroke
				(width 0.1524)
				(type default)
			)
			(layer "F.SilkS")
		)
		(fp_line
			(start 0.7874 0.4064)
			(end -0.7874 0.4064)
			(stroke
				(width 0.1524)
				(type default)
			)
			(layer "F.SilkS")
		)
		(fp_line
			(start -0.7874 -0.4064)
			(end 0.7874 -0.4064)
			(stroke
				(width 0.1524)
				(type default)
			)
			(layer "F.SilkS")
		)
		(fp_line
			(start 0.7874 -0.4064)
			(end 0.7874 0.4064)
			(stroke
				(width 0.1524)
				(type default)
			)
			(layer "F.SilkS")
		)
		(fp_line
			(start -0.67945 0.3048)
			(end -0.67945 -0.305054)
			(stroke
				(width 0.1)
				(type default)
			)
			(layer "F.Fab")
		)
		(fp_line
			(start -0.12065 0.3048)
			(end -0.67945 0.3048)
			(stroke
				(width 0.1)
				(type default)
			)
			(layer "F.Fab")
		)
		(fp_line
			(start 0.120396 0.3048)
			(end 0.120396 0.2794)
			(stroke
				(width 0.1)
				(type default)
			)
			(layer "F.Fab")
		)
		(fp_line
			(start 0.67945 0.3048)
			(end 0.120396 0.3048)
			(stroke
				(width 0.1)
				(type default)
			)
			(layer "F.Fab")
		)
		(fp_line
			(start -0.12065 0.2794)
			(end -0.12065 0.3048)
			(stroke
				(width 0.1)
				(type default)
			)
			(layer "F.Fab")
		)
		(fp_line
			(start 0.120396 0.2794)
			(end -0.12065 0.2794)
			(stroke
				(width 0.1)
				(type default)
			)
			(layer "F.Fab")
		)
		(fp_line
			(start -0.12065 -0.2794)
			(end 0.12065 -0.2794)
			(stroke
				(width 0.1)
				(type default)
			)
			(layer "F.Fab")
		)
		(fp_line
			(start 0.12065 -0.2794)
			(end 0.12065 -0.3048)
			(stroke
				(width 0.1)
				(type default)
			)
			(layer "F.Fab")
		)
		(fp_line
			(start 0.12065 -0.3048)
			(end 0.67945 -0.3048)
			(stroke
				(width 0.1)
				(type default)
			)
			(layer "F.Fab")
		)
		(fp_line
			(start 0.67945 -0.3048)
			(end 0.67945 0.3048)
			(stroke
				(width 0.1)
				(type default)
			)
			(layer "F.Fab")
		)
		(fp_line
			(start -0.67945 -0.305054)
			(end -0.12065 -0.305054)
			(stroke
				(width 0.1)
				(type default)
			)
			(layer "F.Fab")
		)
		(fp_line
			(start -0.12065 -0.305054)
			(end -0.12065 -0.2794)
			(stroke
				(width 0.1)
				(type default)
			)
			(layer "F.Fab")
		)
		(pad "1" smd circle
			(at -0.40005 0 270)
			(size 0 0)
			(layers "F.Cu" "F.Mask" "F.Paste")
			(net "P3V3_AUX")
		)
		(pad "2" smd circle
			(at 0.40005 0 270)
			(size 0 0)
			(layers "F.Cu" "F.Mask" "F.Paste")
			(net "TCA9539_0_ADD0")
		)
	)
	(footprint ""
		(layer "F.Cu")
		(at 97.821242 -414.771586 -90)
		(property "Reference" "R4195"
			(at 0 0 270)
			(layer "F.SilkS")
			(hide yes)
			(effects
				(font
					(size 1.27 1.27)
				)
			)
		)
		(property "Value" ""
			(at 0 0 270)
			(layer "F.Fab")
			(effects
				(font
					(size 1.27 1.27)
				)
			)
		)
		(duplicate_pad_numbers_are_jumpers no)
		(fp_line
			(start -0.7874 0.4064)
			(end -0.7874 -0.4064)
			(stroke
				(width 0.1524)
				(type default)
			)
			(layer "F.SilkS")
		)
		(fp_line
			(start 0.7874 0.4064)
			(end -0.7874 0.4064)
			(stroke
				(width 0.1524)
				(type default)
			)
			(layer "F.SilkS")
		)
		(fp_line
			(start -0.7874 -0.4064)
			(end 0.7874 -0.4064)
			(stroke
				(width 0.1524)
				(type default)
			)
			(layer "F.SilkS")
		)
		(fp_line
			(start 0.7874 -0.4064)
			(end 0.7874 0.4064)
			(stroke
				(width 0.1524)
				(type default)
			)
			(layer "F.SilkS")
		)
		(fp_line
			(start -0.67945 0.3048)
			(end -0.67945 -0.305054)
			(stroke
				(width 0.1)
				(type default)
			)
			(layer "F.Fab")
		)
		(fp_line
			(start -0.12065 0.3048)
			(end -0.67945 0.3048)
			(stroke
				(width 0.1)
				(type default)
			)
			(layer "F.Fab")
		)
		(fp_line
			(start 0.120396 0.3048)
			(end 0.120396 0.2794)
			(stroke
				(width 0.1)
				(type default)
			)
			(layer "F.Fab")
		)
		(fp_line
			(start 0.67945 0.3048)
			(end 0.120396 0.3048)
			(stroke
				(width 0.1)
				(type default)
			)
			(layer "F.Fab")
		)
		(fp_line
			(start -0.12065 0.2794)
			(end -0.12065 0.3048)
			(stroke
				(width 0.1)
				(type default)
			)
			(layer "F.Fab")
		)
		(fp_line
			(start 0.120396 0.2794)
			(end -0.12065 0.2794)
			(stroke
				(width 0.1)
				(type default)
			)
			(layer "F.Fab")
		)
		(fp_line
			(start -0.12065 -0.2794)
			(end 0.12065 -0.2794)
			(stroke
				(width 0.1)
				(type default)
			)
			(layer "F.Fab")
		)
		(fp_line
			(start 0.12065 -0.2794)
			(end 0.12065 -0.3048)
			(stroke
				(width 0.1)
				(type default)
			)
			(layer "F.Fab")
		)
		(fp_line
			(start 0.12065 -0.3048)
			(end 0.67945 -0.3048)
			(stroke
				(width 0.1)
				(type default)
			)
			(layer "F.Fab")
		)
		(fp_line
			(start 0.67945 -0.3048)
			(end 0.67945 0.3048)
			(stroke
				(width 0.1)
				(type default)
			)
			(layer "F.Fab")
		)
		(fp_line
			(start -0.67945 -0.305054)
			(end -0.12065 -0.305054)
			(stroke
				(width 0.1)
				(type default)
			)
			(layer "F.Fab")
		)
		(fp_line
			(start -0.12065 -0.305054)
			(end -0.12065 -0.2794)
			(stroke
				(width 0.1)
				(type default)
			)
			(layer "F.Fab")
		)
		(pad "1" smd circle
			(at -0.40005 0 270)
			(size 0 0)
			(layers "F.Cu" "F.Mask" "F.Paste")
			(net "U272_2_ADD1")
		)
		(pad "2" smd circle
			(at 0.40005 0 270)
			(size 0 0)
			(layers "F.Cu" "F.Mask" "F.Paste")
			(net "GND")
		)
	)
)
